# T6G (Grand Teton) — schematic netlist excerpt (pin names and nets, part order shuffled) for the footprints in the layout excerpt that follows; sources: Cadence DE-HDL packaged netlist, KiCad conversion of 04192023_DAF0TMB3IC0_F0TG_MB_C_brd_V02_OCP.brd

PC365  Q_CAP  1UF 16V 10% X6S  pkg C0402  page 217 : A = PVDDCR_CPU1_P1_VCC ; B = GND

U193  MAX11617EEET  MAX11617EEE+T EMPTY  pkg QSOP16_0-635_4-9X3-89  page 257
  \ain11||ref\  = MAX11617_VREF_R
  AIN10  = GND
  AIN9  = GND
  AIN8  = GND
  AIN0  = P12V_AUX_ADC_MAM
  AIN1  = P12V_OCP_SFF_ISENSE_MAM
  AIN2  = P12V_OCP_V3_2_ISENSE_MAM
  AIN3  = P5V_ADC_MAM
  AIN4  = P3V3_ADC_MAM
  AIN5  = P3V3_AUX_ADC_MAM
  AIN6  = P3V3_PDB_AUX_ADC_MAM
  AIN7  = P12V_E1S_0_ISENSE_MAM
  SCL  = SMB_SEN_MAM_3V3AUX_SCL
  SDA  = SMB_SEN_MAM_3V3AUX_SDA
  GND  = GND
  VDD  = P3V3_MAX11617_VDD

(kicad_pcb
	(version 20260206)
	(generator "pcbnew")
	(generator_version "10.0")
	(general
		(thickness 1.6)
		(legacy_teardrops no)
	)
	(paper "A4")
	(title_block
		(title "04192023_DAF0TMB3IC0_F0TG_MB_C_brd_V02_OCP.brd")
		(comment 1 "Grand Teton / footprints 3055-3056 of 8354")
	)
	(layers
		(0 "F.Cu" signal "TOP")
		(4 "In1.Cu" signal "GND")
		(6 "In2.Cu" signal "IN1")
		(8 "In3.Cu" signal "GND1")
		(10 "In4.Cu" signal "IN2")
		(12 "In5.Cu" signal "GND2")
		(14 "In6.Cu" signal "IN3")
		(16 "In7.Cu" signal "GND3")
		(18 "In8.Cu" signal "VCC")
		(20 "In9.Cu" signal "VCC1")
		(22 "In10.Cu" signal "GND4")
		(24 "In11.Cu" signal "IN4")
		(26 "In12.Cu" signal "GND5")
		(28 "In13.Cu" signal "IN5")
		(30 "In14.Cu" signal "GND6")
		(32 "In15.Cu" signal "IN6")
		(34 "In16.Cu" signal "GND7")
		(2 "B.Cu" signal "BOTTOM")
		(9 "F.Adhes" user "F.Adhesive")
		(11 "B.Adhes" user "B.Adhesive")
		(13 "F.Paste" user "Package Geometry/Pastemask Top")
		(15 "B.Paste" user "Package Geometry/Pastemask Bottom")
		(5 "F.SilkS" user "Ref Des/Silkscreen Top")
		(7 "B.SilkS" user "Ref Des/Silkscreen Bottom")
		(1 "F.Mask" user "Board Geometry/Soldermask Top")
		(3 "B.Mask" user "Board Geometry/Soldermask Bottom")
		(17 "Dwgs.User" user "User.Drawings")
		(19 "Cmts.User" user "User.Comments")
		(21 "Eco1.User" user "User.Eco1")
		(23 "Eco2.User" user "User.Eco2")
		(25 "Edge.Cuts" user "Board Geometry/Outline")
		(27 "Margin" user)
		(31 "F.CrtYd" user "Package Geometry/Place Bound Top")
		(29 "B.CrtYd" user "Package Geometry/Place Bound Bottom")
		(35 "F.Fab" user "Ref Des/Assembly Top")
		(33 "B.Fab" user "Ref Des/Assembly Bottom")
	)
	(footprint ""
		(layer "F.Cu")
		(at 36.837112 -368.455448 90)
		(property "Reference" "PC365"
			(at 0 0 90)
			(layer "F.SilkS")
			(hide yes)
			(effects
				(font
					(size 1.27 1.27)
				)
			)
		)
		(property "Value" ""
			(at 0 0 90)
			(layer "F.Fab")
			(effects
				(font
					(size 1.27 1.27)
				)
			)
		)
		(duplicate_pad_numbers_are_jumpers no)
		(fp_line
			(start 0.7874 -0.4064)
			(end 0.7874 0.4064)
			(stroke
				(width 0.1524)
				(type default)
			)
			(layer "F.SilkS")
		)
		(fp_line
			(start -0.7874 -0.4064)
			(end 0.7874 -0.4064)
			(stroke
				(width 0.1524)
				(type default)
			)
			(layer "F.SilkS")
		)
		(fp_line
			(start 0.7874 0.4064)
			(end -0.7874 0.4064)
			(stroke
				(width 0.1524)
				(type default)
			)
			(layer "F.SilkS")
		)
		(fp_line
			(start -0.7874 0.4064)
			(end -0.7874 -0.4064)
			(stroke
				(width 0.1524)
				(type default)
			)
			(layer "F.SilkS")
		)
		(fp_line
			(start -0.12065 -0.305054)
			(end -0.12065 -0.2794)
			(stroke
				(width 0.1)
				(type default)
			)
			(layer "F.Fab")
		)
		(fp_line
			(start -0.67945 -0.305054)
			(end -0.12065 -0.305054)
			(stroke
				(width 0.1)
				(type default)
			)
			(layer "F.Fab")
		)
		(fp_line
			(start 0.67945 -0.3048)
			(end 0.67945 0.3048)
			(stroke
				(width 0.1)
				(type default)
			)
			(layer "F.Fab")
		)
		(fp_line
			(start 0.12065 -0.3048)
			(end 0.67945 -0.3048)
			(stroke
				(width 0.1)
				(type default)
			)
			(layer "F.Fab")
		)
		(fp_line
			(start 0.12065 -0.2794)
			(end 0.12065 -0.3048)
			(stroke
				(width 0.1)
				(type default)
			)
			(layer "F.Fab")
		)
		(fp_line
			(start -0.12065 -0.2794)
			(end 0.12065 -0.2794)
			(stroke
				(width 0.1)
				(type default)
			)
			(layer "F.Fab")
		)
		(fp_line
			(start 0.120396 0.2794)
			(end -0.12065 0.2794)
			(stroke
				(width 0.1)
				(type default)
			)
			(layer "F.Fab")
		)
		(fp_line
			(start -0.12065 0.2794)
			(end -0.12065 0.3048)
			(stroke
				(width 0.1)
				(type default)
			)
			(layer "F.Fab")
		)
		(fp_line
			(start 0.67945 0.3048)
			(end 0.120396 0.3048)
			(stroke
				(width 0.1)
				(type default)
			)
			(layer "F.Fab")
		)
		(fp_line
			(start 0.120396 0.3048)
			(end 0.120396 0.2794)
			(stroke
				(width 0.1)
				(type default)
			)
			(layer "F.Fab")
		)
		(fp_line
			(start -0.12065 0.3048)
			(end -0.67945 0.3048)
			(stroke
				(width 0.1)
				(type default)
			)
			(layer "F.Fab")
		)
		(fp_line
			(start -0.67945 0.3048)
			(end -0.67945 -0.305054)
			(stroke
				(width 0.1)
				(type default)
			)
			(layer "F.Fab")
		)
		(pad "1" smd circle
			(at -0.40005 0 90)
			(size 0 0)
			(layers "F.Cu" "F.Mask" "F.Paste")
			(net "PVDDCR_CPU1_P1_VCC")
		)
		(pad "2" smd circle
			(at 0.40005 0 90)
			(size 0 0)
			(layers "F.Cu" "F.Mask" "F.Paste")
			(net "GND")
		)
	)
	(footprint ""
		(layer "F.Cu")
		(at 322.653152 -34.620962)
		(property "Reference" "U193"
			(at -1.712468 3.20294 0)
			(unlocked yes)
			(layer "F.SilkS")
			(effects
				(font
					(size 0.7874 0.5842)
					(thickness 0.1524)
				)
				(justify left)
			)
		)
		(property "Value" ""
			(at 0 0 0)
			(layer "F.Fab")
			(effects
				(font
					(size 1.27 1.27)
				)
			)
		)
		(duplicate_pad_numbers_are_jumpers no)
		(fp_line
			(start -1.715516 -2.489962)
			(end -1.715516 2.489962)
			(stroke
				(width 0.1524)
				(type default)
			)
			(layer "F.SilkS")
		)
		(fp_line
			(start -1.715516 2.489962)
			(end 1.715516 2.489962)
			(stroke
				(width 0.1524)
				(type default)
			)
			(layer "F.SilkS")
		)
		(fp_line
			(start -1.092962 -2.489962)
			(end -1.715516 -2.489962)
			(stroke
				(width 0.1524)
				(type default)
			)
			(layer "F.SilkS")
		)
		(fp_line
			(start 0 -1.397)
			(end -1.092962 -2.489962)
			(stroke
				(width 0.1524)
				(type default)
			)
			(layer "F.SilkS")
		)
		(fp_line
			(start 1.092962 -2.489962)
			(end 0 -1.397)
			(stroke
				(width 0.1524)
				(type default)
			)
			(layer "F.SilkS")
		)
		(fp_line
			(start 1.715516 -2.489962)
			(end 1.092962 -2.489962)
			(stroke
				(width 0.1524)
				(type default)
			)
			(layer "F.SilkS")
		)
		(fp_line
			(start 1.715516 2.489962)
			(end 1.715516 -2.489962)
			(stroke
				(width 0.1524)
				(type default)
			)
			(layer "F.SilkS")
		)
		(fp_poly
			(pts
				(xy -3.203956 -3.79984) (xy -2.187956 -3.79984) (xy -2.695956 -2.78384)
			)
			(stroke
				(width 0)
				(type default)
			)
			(fill yes)
			(layer "F.SilkS")
		)
		(fp_line
			(start -1.994916 -2.489962)
			(end -1.994916 2.489962)
			(stroke
				(width 0.1)
				(type default)
			)
			(layer "F.Fab")
		)
		(fp_line
			(start -1.994916 2.489962)
			(end 1.994916 2.489962)
			(stroke
				(width 0.1)
				(type default)
			)
			(layer "F.Fab")
		)
		(fp_line
			(start 1.994916 -2.489962)
			(end -1.994916 -2.489962)
			(stroke
				(width 0.1)
				(type default)
			)
			(layer "F.Fab")
		)
		(fp_line
			(start 1.994916 2.489962)
			(end 1.994916 -2.489962)
			(stroke
				(width 0.1)
				(type default)
			)
			(layer "F.Fab")
		)
		(fp_poly
			(pts
				(xy -4.699 -2.7305) (xy -4.699 -1.7145) (xy -3.683 -2.2225)
			)
			(stroke
				(width 0)
				(type default)
			)
			(fill yes)
			(layer "F.Fab")
		)
		(pad "1" smd rect
			(at -2.655062 -2.2225 90)
			(size 0.381 1.6002)
			(layers "F.Cu" "F.Mask" "F.Paste")
			(net "MAX11617_VREF_R")
		)
		(pad "2" smd rect
			(at -2.655062 -1.5875 90)
			(size 0.381 1.6002)
			(layers "F.Cu" "F.Mask" "F.Paste")
			(net "GND")
		)
		(pad "3" smd rect
			(at -2.655062 -0.9525 90)
			(size 0.381 1.6002)
			(layers "F.Cu" "F.Mask" "F.Paste")
			(net "GND")
		)
		(pad "4" smd rect
			(at -2.655062 -0.3175 90)
			(size 0.381 1.6002)
			(layers "F.Cu" "F.Mask" "F.Paste")
			(net "GND")
		)
		(pad "5" smd rect
			(at -2.655062 0.3175 90)
			(size 0.381 1.6002)
			(layers "F.Cu" "F.Mask" "F.Paste")
			(net "P12V_AUX_ADC_MAM")
		)
		(pad "6" smd rect
			(at -2.655062 0.9525 90)
			(size 0.381 1.6002)
			(layers "F.Cu" "F.Mask" "F.Paste")
			(net "P12V_OCP_SFF_ISENSE_MAM")
		)
		(pad "7" smd rect
			(at -2.655062 1.5875 90)
			(size 0.381 1.6002)
			(layers "F.Cu" "F.Mask" "F.Paste")
			(net "P12V_OCP_V3_2_ISENSE_MAM")
		)
		(pad "8" smd rect
			(at -2.655062 2.2225 90)
			(size 0.381 1.6002)
			(layers "F.Cu" "F.Mask" "F.Paste")
			(net "P5V_ADC_MAM")
		)
		(pad "9" smd rect
			(at 2.655062 2.2225 90)
			(size 0.381 1.6002)
			(layers "F.Cu" "F.Mask" "F.Paste")
			(net "P3V3_ADC_MAM")
		)
		(pad "10" smd rect
			(at 2.655062 1.5875 90)
			(size 0.381 1.6002)
			(layers "F.Cu" "F.Mask" "F.Paste")
			(net "P3V3_AUX_ADC_MAM")
		)
		(pad "11" smd rect
			(at 2.655062 0.9525 90)
			(size 0.381 1.6002)
			(layers "F.Cu" "F.Mask" "F.Paste")
			(net "P3V3_PDB_AUX_ADC_MAM")
		)
		(pad "12" smd rect
			(at 2.655062 0.3175 90)
			(size 0.381 1.6002)
			(layers "F.Cu" "F.Mask" "F.Paste")
			(net "P12V_E1S_0_ISENSE_MAM")
		)
		(pad "13" smd rect
			(at 2.655062 -0.3175 90)
			(size 0.381 1.6002)
			(layers "F.Cu" "F.Mask" "F.Paste")
			(net "SMB_SEN_MAM_3V3AUX_SCL")
		)
		(pad "14" smd rect
			(at 2.655062 -0.9525 90)
			(size 0.381 1.6002)
			(layers "F.Cu" "F.Mask" "F.Paste")
			(net "SMB_SEN_MAM_3V3AUX_SDA")
		)
		(pad "15" smd rect
			(at 2.655062 -1.5875 90)
			(size 0.381 1.6002)
			(layers "F.Cu" "F.Mask" "F.Paste")
			(net "GND")
		)
		(pad "16" smd rect
			(at 2.655062 -2.2225 90)
			(size 0.381 1.6002)
			(layers "F.Cu" "F.Mask" "F.Paste")
			(net "P3V3_MAX11617_VDD")
		)
	)
)
